# T6G (Grand Teton) — schematic netlist excerpt (pin names and nets, part order shuffled) for the footprints in the layout excerpt that follows; sources: Cadence DE-HDL packaged netlist, KiCad conversion of 04192023_DAF0TMB3IC0_F0TG_MB_C_brd_V02_OCP.brd

R549  Q_RES  4.7K 5% EMPTY  pkg 0402LF  page 55 : A = CPU1_SLP_S3_N ; B = PVDD18_S5_P1
R6140  Q_RES  1K 1% EMPTY  pkg 0402LF  page 84 : A = P3V3_AUX ; B = FM_BOARD_BMC_SKU_ID0

(kicad_pcb
	(version 20260206)
	(generator "pcbnew")
	(generator_version "10.0")
	(general
		(thickness 1.6)
		(legacy_teardrops no)
	)
	(paper "A4")
	(title_block
		(title "04192023_DAF0TMB3IC0_F0TG_MB_C_brd_V02_OCP.brd")
		(comment 1 "Grand Teton / footprints 7488-7489 of 8354")
	)
	(layers
		(0 "F.Cu" signal "TOP")
		(4 "In1.Cu" signal "GND")
		(6 "In2.Cu" signal "IN1")
		(8 "In3.Cu" signal "GND1")
		(10 "In4.Cu" signal "IN2")
		(12 "In5.Cu" signal "GND2")
		(14 "In6.Cu" signal "IN3")
		(16 "In7.Cu" signal "GND3")
		(18 "In8.Cu" signal "VCC")
		(20 "In9.Cu" signal "VCC1")
		(22 "In10.Cu" signal "GND4")
		(24 "In11.Cu" signal "IN4")
		(26 "In12.Cu" signal "GND5")
		(28 "In13.Cu" signal "IN5")
		(30 "In14.Cu" signal "GND6")
		(32 "In15.Cu" signal "IN6")
		(34 "In16.Cu" signal "GND7")
		(2 "B.Cu" signal "BOTTOM")
		(9 "F.Adhes" user "F.Adhesive")
		(11 "B.Adhes" user "B.Adhesive")
		(13 "F.Paste" user "Package Geometry/Pastemask Top")
		(15 "B.Paste" user "Package Geometry/Pastemask Bottom")
		(5 "F.SilkS" user "Ref Des/Silkscreen Top")
		(7 "B.SilkS" user "Ref Des/Silkscreen Bottom")
		(1 "F.Mask" user "Board Geometry/Soldermask Top")
		(3 "B.Mask" user "Board Geometry/Soldermask Bottom")
		(17 "Dwgs.User" user "User.Drawings")
		(19 "Cmts.User" user "User.Comments")
		(21 "Eco1.User" user "User.Eco1")
		(23 "Eco2.User" user "User.Eco2")
		(25 "Edge.Cuts" user "Board Geometry/Outline")
		(27 "Margin" user)
		(31 "F.CrtYd" user "Package Geometry/Place Bound Top")
		(29 "B.CrtYd" user "Package Geometry/Place Bound Bottom")
		(35 "F.Fab" user "Ref Des/Assembly Top")
		(33 "B.Fab" user "Ref Des/Assembly Bottom")
	)
	(footprint ""
		(layer "B.Cu")
		(at 156.154374 -324.781672 180)
		(property "Reference" "R549"
			(at 0 0 0)
			(layer "B.SilkS")
			(hide yes)
			(effects
				(font
					(size 1.27 1.27)
				)
				(justify mirror)
			)
		)
		(property "Value" ""
			(at 0 0 0)
			(layer "B.Fab")
			(effects
				(font
					(size 1.27 1.27)
				)
				(justify mirror)
			)
		)
		(duplicate_pad_numbers_are_jumpers no)
		(fp_line
			(start 0.7874 0.4064)
			(end 0.7874 -0.4064)
			(stroke
				(width 0.1524)
				(type default)
			)
			(layer "B.SilkS")
		)
		(fp_line
			(start 0.7874 -0.4064)
			(end -0.7874 -0.4064)
			(stroke
				(width 0.1524)
				(type default)
			)
			(layer "B.SilkS")
		)
		(fp_line
			(start -0.7874 0.4064)
			(end 0.7874 0.4064)
			(stroke
				(width 0.1524)
				(type default)
			)
			(layer "B.SilkS")
		)
		(fp_line
			(start -0.7874 -0.4064)
			(end -0.7874 0.4064)
			(stroke
				(width 0.1524)
				(type default)
			)
			(layer "B.SilkS")
		)
		(fp_line
			(start 0.67945 0.3048)
			(end 0.67945 -0.305054)
			(stroke
				(width 0.1)
				(type default)
			)
			(layer "B.Fab")
		)
		(fp_line
			(start 0.67945 -0.305054)
			(end 0.12065 -0.305054)
			(stroke
				(width 0.1)
				(type default)
			)
			(layer "B.Fab")
		)
		(fp_line
			(start 0.12065 0.3048)
			(end 0.67945 0.3048)
			(stroke
				(width 0.1)
				(type default)
			)
			(layer "B.Fab")
		)
		(fp_line
			(start 0.12065 0.2794)
			(end 0.12065 0.3048)
			(stroke
				(width 0.1)
				(type default)
			)
			(layer "B.Fab")
		)
		(fp_line
			(start 0.12065 -0.2794)
			(end -0.12065 -0.2794)
			(stroke
				(width 0.1)
				(type default)
			)
			(layer "B.Fab")
		)
		(fp_line
			(start 0.12065 -0.305054)
			(end 0.12065 -0.2794)
			(stroke
				(width 0.1)
				(type default)
			)
			(layer "B.Fab")
		)
		(fp_line
			(start -0.120396 0.3048)
			(end -0.120396 0.2794)
			(stroke
				(width 0.1)
				(type default)
			)
			(layer "B.Fab")
		)
		(fp_line
			(start -0.120396 0.2794)
			(end 0.12065 0.2794)
			(stroke
				(width 0.1)
				(type default)
			)
			(layer "B.Fab")
		)
		(fp_line
			(start -0.12065 -0.2794)
			(end -0.12065 -0.3048)
			(stroke
				(width 0.1)
				(type default)
			)
			(layer "B.Fab")
		)
		(fp_line
			(start -0.12065 -0.3048)
			(end -0.67945 -0.3048)
			(stroke
				(width 0.1)
				(type default)
			)
			(layer "B.Fab")
		)
		(fp_line
			(start -0.67945 0.3048)
			(end -0.120396 0.3048)
			(stroke
				(width 0.1)
				(type default)
			)
			(layer "B.Fab")
		)
		(fp_line
			(start -0.67945 -0.3048)
			(end -0.67945 0.3048)
			(stroke
				(width 0.1)
				(type default)
			)
			(layer "B.Fab")
		)
		(pad "1" smd circle
			(at 0.40005 0)
			(size 0 0)
			(layers "B.Cu" "B.Mask" "B.Paste")
			(net "CPU1_SLP_S3_N")
		)
		(pad "2" smd circle
			(at -0.40005 0)
			(size 0 0)
			(layers "B.Cu" "B.Mask" "B.Paste")
			(net "PVDD18_S5_P1")
		)
	)
	(footprint ""
		(layer "B.Cu")
		(at 164.044376 -111.637572 180)
		(property "Reference" "R6140"
			(at 0 0 0)
			(layer "B.SilkS")
			(hide yes)
			(effects
				(font
					(size 1.27 1.27)
				)
				(justify mirror)
			)
		)
		(property "Value" ""
			(at 0 0 0)
			(layer "B.Fab")
			(effects
				(font
					(size 1.27 1.27)
				)
				(justify mirror)
			)
		)
		(duplicate_pad_numbers_are_jumpers no)
		(fp_line
			(start 0.7874 0.4064)
			(end 0.7874 -0.4064)
			(stroke
				(width 0.1524)
				(type default)
			)
			(layer "B.SilkS")
		)
		(fp_line
			(start 0.7874 -0.4064)
			(end -0.7874 -0.4064)
			(stroke
				(width 0.1524)
				(type default)
			)
			(layer "B.SilkS")
		)
		(fp_line
			(start -0.7874 0.4064)
			(end 0.7874 0.4064)
			(stroke
				(width 0.1524)
				(type default)
			)
			(layer "B.SilkS")
		)
		(fp_line
			(start -0.7874 -0.4064)
			(end -0.7874 0.4064)
			(stroke
				(width 0.1524)
				(type default)
			)
			(layer "B.SilkS")
		)
		(fp_line
			(start 0.67945 0.3048)
			(end 0.67945 -0.305054)
			(stroke
				(width 0.1)
				(type default)
			)
			(layer "B.Fab")
		)
		(fp_line
			(start 0.67945 -0.305054)
			(end 0.12065 -0.305054)
			(stroke
				(width 0.1)
				(type default)
			)
			(layer "B.Fab")
		)
		(fp_line
			(start 0.12065 0.3048)
			(end 0.67945 0.3048)
			(stroke
				(width 0.1)
				(type default)
			)
			(layer "B.Fab")
		)
		(fp_line
			(start 0.12065 0.2794)
			(end 0.12065 0.3048)
			(stroke
				(width 0.1)
				(type default)
			)
			(layer "B.Fab")
		)
		(fp_line
			(start 0.12065 -0.2794)
			(end -0.12065 -0.2794)
			(stroke
				(width 0.1)
				(type default)
			)
			(layer "B.Fab")
		)
		(fp_line
			(start 0.12065 -0.305054)
			(end 0.12065 -0.2794)
			(stroke
				(width 0.1)
				(type default)
			)
			(layer "B.Fab")
		)
		(fp_line
			(start -0.120396 0.3048)
			(end -0.120396 0.2794)
			(stroke
				(width 0.1)
				(type default)
			)
			(layer "B.Fab")
		)
		(fp_line
			(start -0.120396 0.2794)
			(end 0.12065 0.2794)
			(stroke
				(width 0.1)
				(type default)
			)
			(layer "B.Fab")
		)
		(fp_line
			(start -0.12065 -0.2794)
			(end -0.12065 -0.3048)
			(stroke
				(width 0.1)
				(type default)
			)
			(layer "B.Fab")
		)
		(fp_line
			(start -0.12065 -0.3048)
			(end -0.67945 -0.3048)
			(stroke
				(width 0.1)
				(type default)
			)
			(layer "B.Fab")
		)
		(fp_line
			(start -0.67945 0.3048)
			(end -0.120396 0.3048)
			(stroke
				(width 0.1)
				(type default)
			)
			(layer "B.Fab")
		)
		(fp_line
			(start -0.67945 -0.3048)
			(end -0.67945 0.3048)
			(stroke
				(width 0.1)
				(type default)
			)
			(layer "B.Fab")
		)
		(pad "1" smd circle
			(at 0.40005 0)
			(size 0 0)
			(layers "B.Cu" "B.Mask" "B.Paste")
			(net "P3V3_AUX")
		)
		(pad "2" smd circle
			(at -0.40005 0)
			(size 0 0)
			(layers "B.Cu" "B.Mask" "B.Paste")
			(net "FM_BOARD_BMC_SKU_ID0")
		)
	)
)
